FILE_TYPE = CONNECTIVITY;
{Allegro Design Entry HDL 16.6-p007 (v16-6-112F) 10/10/2012}
"PAGE_NUMBER" = 31;
0"NC";
1"P3E_CPU0_PE2_SS_TXN<15:0>";
2"P3E_CPU0_PE2_SS_TXP<15:0>";
3"P3E_CPU0_PE2_SS_RXN<15:0>";
4"P3E_CPU0_PE2_SS_RXP<15:0>";
5"P3E_CPU0_PE2_SS_TXN<14>";
6"P3E_CPU0_PE2_SS_RXP<15>";
7"P3E_CPU0_PE2_SS_RXP<8>";
8"P3E_CPU0_PE2_SS_RXP<10>";
9"P3E_CPU0_PE2_SS_RXP<9>";
10"P3E_CPU0_PE2_SS_RXN<2>";
11"P3E_CPU0_PE2_SS_RXP<0>";
12"P3E_CPU0_PE2_SS_RXP<1>";
13"P3E_CPU0_PE2_SS_RXP<2>";
14"P3E_CPU0_PE2_SS_RXN<0>";
15"P3E_CPU0_PE2_SS_RXN<1>";
16"P3E_CPU0_PE2_SS_RXN<3>";
17"P3E_CPU0_PE2_SS_RXP<3>";
18"P3E_CPU0_PE2_SS_RXP<4>";
19"P3E_CPU0_PE2_SS_RXP<5>";
20"P3E_CPU0_PE2_SS_RXP<6>";
21"P3E_CPU0_PE2_SS_RXP<7>";
22"P3E_CPU0_PE2_SS_RXP<11>";
23"P3E_CPU0_PE2_SS_RXP<12>";
24"P3E_CPU0_PE2_SS_RXP<13>";
25"P3E_CPU0_PE2_SS_RXP<14>";
26"P3E_CPU0_PE2_SS_RXN<4>";
27"P3E_CPU0_PE2_SS_RXN<5>";
28"P3E_CPU0_PE2_SS_RXN<6>";
29"P3E_CPU0_PE2_SS_RXN<7>";
30"P3E_CPU0_PE2_SS_RXN<8>";
31"P3E_CPU0_PE2_SS_RXN<9>";
32"P3E_CPU0_PE2_SS_RXN<10>";
33"P3E_CPU0_PE2_SS_RXN<11>";
34"P3E_CPU0_PE2_SS_RXN<12>";
35"P3E_CPU0_PE2_SS_RXN<13>";
36"P3E_CPU0_PE2_SS_RXN<14>";
37"P3E_CPU0_PE2_SS_RXN<15>";
38"P3E_CPU0_PE2_SS_TXP<0>";
39"P3E_CPU0_PE2_SS_TXP<1>";
40"P3E_CPU0_PE2_SS_TXP<2>";
41"P3E_CPU0_PE2_SS_TXN<0>";
42"P3E_CPU0_PE2_SS_TXN<1>";
43"P3E_CPU0_PE2_SS_TXN<2>";
44"P3E_CPU0_PE2_SS_TXN<3>";
45"P3E_CPU0_PE2_SS_TXP<3>";
46"P3E_CPU0_PE2_SS_TXP<4>";
47"P3E_CPU0_PE2_SS_TXP<5>";
48"P3E_CPU0_PE2_SS_TXP<6>";
49"P3E_CPU0_PE2_SS_TXP<7>";
50"P3E_CPU0_PE2_SS_TXP<8>";
51"P3E_CPU0_PE2_SS_TXP<9>";
52"P3E_CPU0_PE2_SS_TXP<10>";
53"P3E_CPU0_PE2_SS_TXP<11>";
54"P3E_CPU0_PE2_SS_TXP<12>";
55"P3E_CPU0_PE2_SS_TXP<13>";
56"P3E_CPU0_PE2_SS_TXP<14>";
57"P3E_CPU0_PE2_SS_TXP<15>";
58"P3E_CPU0_PE2_SS_TXN<4>";
59"P3E_CPU0_PE2_SS_TXN<5>";
60"P3E_CPU0_PE2_SS_TXN<6>";
61"P3E_CPU0_PE2_SS_TXN<7>";
62"P3E_CPU0_PE2_SS_TXN<8>";
63"P3E_CPU0_PE2_SS_TXN<9>";
64"P3E_CPU0_PE2_SS_TXN<10>";
65"P3E_CPU0_PE2_SS_TXN<11>";
66"P3E_CPU0_PE2_SS_TXN<12>";
67"P3E_CPU0_PE2_SS_TXN<13>";
68"P3E_CPU0_PE2_SS_TXN<15>";
%"TAP"
"1","(-5450,1950)","2","mstr_standard","I10";
;
CDS_LIB"mstr_standard"
BODY_TYPE"PLUMBING"
HDL_TAP"TRUE";
"B \NAC \NWC"4;
"S \NAC"
BN"1"12;
%"TAP"
"1","(-5300,2650)","2","mstr_standard","I100";
;
CDS_LIB"mstr_standard"
BODY_TYPE"PLUMBING"
HDL_TAP"TRUE";
"B \NAC \NWC"3;
"S \NAC"
BN"8"30;
%"TAP"
"1","(-5450,3000)","2","mstr_standard","I101";
;
CDS_LIB"mstr_standard"
BODY_TYPE"PLUMBING"
HDL_TAP"TRUE";
"B \NAC \NWC"4;
"S \NAC"
BN"10"8;
%"TAP"
"1","(-5450,2950)","2","mstr_standard","I102";
;
CDS_LIB"mstr_standard"
BODY_TYPE"PLUMBING"
HDL_TAP"TRUE";
"B \NAC \NWC"4;
"S \NAC"
BN"9"9;
%"TAP"
"1","(-5450,2900)","2","mstr_standard","I103";
;
CDS_LIB"mstr_standard"
BODY_TYPE"PLUMBING"
HDL_TAP"TRUE";
"B \NAC \NWC"4;
"S \NAC"
BN"8"7;
%"SKX_EXT_B"
"11","(-4025,2600)","0","chpset_lib","I106";
;
CDS_SEC"11"
LOCATION"U5D1"
PART_NUMBER"TBD"
MATERIAL"IC"
PACK_TYPE"BGA1"
CDS_LIB"chpset_lib"
SEC_TYPE"BGA1"
SEC"11"
CDS_LOCATION"U5D1"
ROOM"CPU0";
"PE2_TX_DP<0>"
$PN"CW4"38;
"PE2_TX_DP<1>"
$PN"CU2"39;
"PE2_TX_DP<2>"
$PN"CR2"40;
"PE2_TX_DP<3>"
$PN"CP3"45;
"PE2_TX_DP<4>"
$PN"CK1"46;
"PE2_TX_DP<5>"
$PN"CK3"47;
"PE2_TX_DP<6>"
$PN"CE2"48;
"PE2_TX_DP<7>"
$PN"CE4"49;
"PE2_TX_DP<8>"
$PN"CD3"50;
"PE2_TX_DP<9>"
$PN"BY3"51;
"PE2_TX_DP<10>"
$PN"BY5"52;
"PE2_TX_DP<11>"
$PN"BV3"53;
"PE2_TX_DP<12>"
$PN"BR4"54;
"PE2_TX_DP<13>"
$PN"BN4"55;
"PE2_TX_DP<14>"
$PN"BM3"56;
"PE2_TX_DP<15>"
$PN"BK5"57;
"PE2_TX_DN<0>"
$PN"CY3"41;
"PE2_TX_DN<1>"
$PN"CV3"42;
"PE2_TX_DN<2>"
$PN"CT1"43;
"PE2_TX_DN<3>"
$PN"CT3"44;
"PE2_TX_DN<4>"
$PN"CM1"58;
"PE2_TX_DN<5>"
$PN"CL2"59;
"PE2_TX_DN<6>"
$PN"CG2"60;
"PE2_TX_DN<7>"
$PN"CF3"61;
"PE2_TX_DN<8>"
$PN"CC2"62;
"PE2_TX_DN<9>"
$PN"CB3"63;
"PE2_TX_DN<10>"
$PN"CA4"64;
"PE2_TX_DN<11>"
$PN"BW4"65;
"PE2_TX_DN<12>"
$PN"BU4"66;
"PE2_TX_DN<13>"
$PN"BP5"67;
"PE2_TX_DN<14>"
$PN"BL4"5;
"PE2_TX_DN<15>"
$PN"BM5"68;
"PE2_RX_DP<0>"
$PN"CR8"11;
"PE2_RX_DP<1>"
$PN"CM9"12;
"PE2_RX_DP<2>"
$PN"CN8"13;
"PE2_RX_DP<3>"
$PN"CL6"17;
"PE2_RX_DP<4>"
$PN"CH7"18;
"PE2_RX_DP<5>"
$PN"CF7"19;
"PE2_RX_DP<6>"
$PN"CD7"20;
"PE2_RX_DP<7>"
$PN"CC8"21;
"PE2_RX_DP<8>"
$PN"BV9"7;
"PE2_RX_DP<9>"
$PN"BW8"9;
"PE2_RX_DP<10>"
$PN"BU6"8;
"PE2_RX_DP<11>"
$PN"BP7"22;
"PE2_RX_DP<12>"
$PN"BP9"23;
"PE2_RX_DP<13>"
$PN"BM7"24;
"PE2_RX_DP<14>"
$PN"BJ8"25;
"PE2_RX_DP<15>"
$PN"BJ10"6;
"PE2_RX_DN<0>"
$PN"CT9"14;
"PE2_RX_DN<1>"
$PN"CP9"15;
"PE2_RX_DN<2>"
$PN"CP7"10;
"PE2_RX_DN<3>"
$PN"CM7"16;
"PE2_RX_DN<4>"
$PN"CK7"26;
"PE2_RX_DN<5>"
$PN"CG8"27;
"PE2_RX_DN<6>"
$PN"CE6"28;
"PE2_RX_DN<7>"
$PN"CE8"29;
"PE2_RX_DN<8>"
$PN"BY9"30;
"PE2_RX_DN<9>"
$PN"BY7"31;
"PE2_RX_DN<10>"
$PN"BV7"32;
"PE2_RX_DN<11>"
$PN"BT7"33;
"PE2_RX_DN<12>"
$PN"BR8"34;
"PE2_RX_DN<13>"
$PN"BN8"35;
"PE2_RX_DN<14>"
$PN"BL8"36;
"PE2_RX_DN<15>"
$PN"BK9"37;
%"TAP"
"1","(-5450,2000)","2","mstr_standard","I11";
;
CDS_LIB"mstr_standard"
BODY_TYPE"PLUMBING"
HDL_TAP"TRUE";
"B \NAC \NWC"4;
"S \NAC"
BN"2"13;
%"TAP"
"1","(-5450,2400)","2","mstr_standard","I12";
;
CDS_LIB"mstr_standard"
BODY_TYPE"PLUMBING"
HDL_TAP"TRUE";
"B \NAC \NWC"4;
"S \NAC"
BN"4"18;
%"TAP"
"1","(-5300,2150)","2","mstr_standard","I13";
;
CDS_LIB"mstr_standard"
BODY_TYPE"PLUMBING"
HDL_TAP"TRUE";
"B \NAC \NWC"3;
"S \NAC"
BN"4"26;
%"TAP"
"1","(-5300,2250)","2","mstr_standard","I14";
;
CDS_LIB"mstr_standard"
BODY_TYPE"PLUMBING"
HDL_TAP"TRUE";
"B \NAC \NWC"3;
"S \NAC"
BN"6"28;
%"TAP"
"1","(-5300,2300)","2","mstr_standard","I15";
;
CDS_LIB"mstr_standard"
BODY_TYPE"PLUMBING"
HDL_TAP"TRUE";
"B \NAC \NWC"3;
"S \NAC"
BN"7"29;
%"TAP"
"1","(-5300,2200)","2","mstr_standard","I16";
;
CDS_LIB"mstr_standard"
BODY_TYPE"PLUMBING"
HDL_TAP"TRUE";
"B \NAC \NWC"3;
"S \NAC"
BN"5"27;
%"TAP"
"1","(-5450,2550)","2","mstr_standard","I17";
;
CDS_LIB"mstr_standard"
BODY_TYPE"PLUMBING"
HDL_TAP"TRUE";
"B \NAC \NWC"4;
"S \NAC"
BN"7"21;
%"TAP"
"1","(-5450,2450)","2","mstr_standard","I18";
;
CDS_LIB"mstr_standard"
BODY_TYPE"PLUMBING"
HDL_TAP"TRUE";
"B \NAC \NWC"4;
"S \NAC"
BN"5"19;
%"TAP"
"1","(-5450,2500)","2","mstr_standard","I19";
;
CDS_LIB"mstr_standard"
BODY_TYPE"PLUMBING"
HDL_TAP"TRUE";
"B \NAC \NWC"4;
"S \NAC"
BN"6"20;
%"TAP"
"1","(-5300,1650)","2","mstr_standard","I3";
;
CDS_LIB"mstr_standard"
BODY_TYPE"PLUMBING"
HDL_TAP"TRUE";
"B \NAC \NWC"3;
"S \NAC"
BN"0"14;
%"TAP"
"1","(-2675,1650)","0","mstr_standard","I36";
;
CDS_LIB"mstr_standard"
BODY_TYPE"PLUMBING"
HDL_TAP"TRUE";
"B \NAC \NWC"1;
"S \NAC"
BN"0"41;
%"TAP"
"1","(-2825,1900)","0","mstr_standard","I37";
;
CDS_LIB"mstr_standard"
BODY_TYPE"PLUMBING"
HDL_TAP"TRUE";
"B \NAC \NWC"2;
"S \NAC"
BN"0"38;
%"TAP"
"1","(-2675,1700)","0","mstr_standard","I38";
;
CDS_LIB"mstr_standard"
BODY_TYPE"PLUMBING"
HDL_TAP"TRUE";
"B \NAC \NWC"1;
"S \NAC"
BN"1"42;
%"TAP"
"1","(-2675,1750)","0","mstr_standard","I39";
;
CDS_LIB"mstr_standard"
BODY_TYPE"PLUMBING"
HDL_TAP"TRUE";
"B \NAC \NWC"1;
"S \NAC"
BN"2"43;
%"TAP"
"1","(-5300,1700)","2","mstr_standard","I4";
;
CDS_LIB"mstr_standard"
BODY_TYPE"PLUMBING"
HDL_TAP"TRUE";
"B \NAC \NWC"3;
"S \NAC"
BN"1"15;
%"TAP"
"1","(-2675,1800)","0","mstr_standard","I40";
;
CDS_LIB"mstr_standard"
BODY_TYPE"PLUMBING"
HDL_TAP"TRUE";
"B \NAC \NWC"1;
"S \NAC"
BN"3"44;
%"TAP"
"1","(-2825,1950)","0","mstr_standard","I41";
;
CDS_LIB"mstr_standard"
BODY_TYPE"PLUMBING"
HDL_TAP"TRUE";
"B \NAC \NWC"2;
"S \NAC"
BN"1"39;
%"TAP"
"1","(-2825,2000)","0","mstr_standard","I42";
;
CDS_LIB"mstr_standard"
BODY_TYPE"PLUMBING"
HDL_TAP"TRUE";
"B \NAC \NWC"2;
"S \NAC"
BN"2"40;
%"TAP"
"1","(-2825,2050)","0","mstr_standard","I43";
;
CDS_LIB"mstr_standard"
BODY_TYPE"PLUMBING"
HDL_TAP"TRUE";
"B \NAC \NWC"2;
"S \NAC"
BN"3"45;
%"TAP"
"1","(-2675,2150)","0","mstr_standard","I44";
;
CDS_LIB"mstr_standard"
BODY_TYPE"PLUMBING"
HDL_TAP"TRUE";
"B \NAC \NWC"1;
"S \NAC"
BN"4"58;
%"TAP"
"1","(-2825,2400)","0","mstr_standard","I45";
;
CDS_LIB"mstr_standard"
BODY_TYPE"PLUMBING"
HDL_TAP"TRUE";
"B \NAC \NWC"2;
"S \NAC"
BN"4"46;
%"TAP"
"1","(-2675,2200)","0","mstr_standard","I46";
;
CDS_LIB"mstr_standard"
BODY_TYPE"PLUMBING"
HDL_TAP"TRUE";
"B \NAC \NWC"1;
"S \NAC"
BN"5"59;
%"TAP"
"1","(-2675,2300)","0","mstr_standard","I47";
;
CDS_LIB"mstr_standard"
BODY_TYPE"PLUMBING"
HDL_TAP"TRUE";
"B \NAC \NWC"1;
"S \NAC"
BN"7"61;
%"TAP"
"1","(-2675,2250)","0","mstr_standard","I48";
;
CDS_LIB"mstr_standard"
BODY_TYPE"PLUMBING"
HDL_TAP"TRUE";
"B \NAC \NWC"1;
"S \NAC"
BN"6"60;
%"TAP"
"1","(-2825,2550)","0","mstr_standard","I49";
;
CDS_LIB"mstr_standard"
BODY_TYPE"PLUMBING"
HDL_TAP"TRUE";
"B \NAC \NWC"2;
"S \NAC"
BN"7"49;
%"TAP"
"1","(-5300,1750)","2","mstr_standard","I5";
;
CDS_LIB"mstr_standard"
BODY_TYPE"PLUMBING"
HDL_TAP"TRUE";
"B \NAC \NWC"3;
"S \NAC"
BN"2"10;
%"TAP"
"1","(-2825,2450)","0","mstr_standard","I50";
;
CDS_LIB"mstr_standard"
BODY_TYPE"PLUMBING"
HDL_TAP"TRUE";
"B \NAC \NWC"2;
"S \NAC"
BN"5"47;
%"TAP"
"1","(-2825,2500)","0","mstr_standard","I51";
;
CDS_LIB"mstr_standard"
BODY_TYPE"PLUMBING"
HDL_TAP"TRUE";
"B \NAC \NWC"2;
"S \NAC"
BN"6"48;
%"TAP"
"1","(-5300,1800)","2","mstr_standard","I6";
;
CDS_LIB"mstr_standard"
BODY_TYPE"PLUMBING"
HDL_TAP"TRUE";
"B \NAC \NWC"3;
"S \NAC"
BN"3"16;
%"TAP"
"1","(-5450,1900)","2","mstr_standard","I7";
;
CDS_LIB"mstr_standard"
BODY_TYPE"PLUMBING"
HDL_TAP"TRUE";
"B \NAC \NWC"4;
"S \NAC"
BN"0"11;
%"TAP"
"1","(-2675,3200)","0","mstr_standard","I72";
;
CDS_LIB"mstr_standard"
BODY_TYPE"PLUMBING"
HDL_TAP"TRUE";
"B \NAC \NWC"1;
"S \NAC"
BN"13"67;
%"TAP"
"1","(-2675,3300)","0","mstr_standard","I73";
;
CDS_LIB"mstr_standard"
BODY_TYPE"PLUMBING"
HDL_TAP"TRUE";
"B \NAC \NWC"1;
"S \NAC"
BN"15"68;
%"TAP"
"1","(-2675,3250)","0","mstr_standard","I74";
;
CDS_LIB"mstr_standard"
BODY_TYPE"PLUMBING"
HDL_TAP"TRUE";
"B \NAC \NWC"1;
"S \NAC"
BN"14"5;
%"TAP"
"1","(-2675,3150)","0","mstr_standard","I75";
;
CDS_LIB"mstr_standard"
BODY_TYPE"PLUMBING"
HDL_TAP"TRUE";
"B \NAC \NWC"1;
"S \NAC"
BN"12"66;
%"TAP"
"1","(-2825,3500)","0","mstr_standard","I76";
;
CDS_LIB"mstr_standard"
BODY_TYPE"PLUMBING"
HDL_TAP"TRUE";
"B \NAC \NWC"2;
"S \NAC"
BN"14"56;
%"TAP"
"1","(-2825,3550)","0","mstr_standard","I77";
;
CDS_LIB"mstr_standard"
BODY_TYPE"PLUMBING"
HDL_TAP"TRUE";
"B \NAC \NWC"2;
"S \NAC"
BN"15"57;
%"TAP"
"1","(-2825,3450)","0","mstr_standard","I78";
;
CDS_LIB"mstr_standard"
BODY_TYPE"PLUMBING"
HDL_TAP"TRUE";
"B \NAC \NWC"2;
"S \NAC"
BN"13"55;
%"TAP"
"1","(-2825,3400)","0","mstr_standard","I79";
;
CDS_LIB"mstr_standard"
BODY_TYPE"PLUMBING"
HDL_TAP"TRUE";
"B \NAC \NWC"2;
"S \NAC"
BN"12"54;
%"TAP"
"1","(-2825,3050)","0","mstr_standard","I80";
;
CDS_LIB"mstr_standard"
BODY_TYPE"PLUMBING"
HDL_TAP"TRUE";
"B \NAC \NWC"2;
"S \NAC"
BN"11"53;
%"TAP"
"1","(-2675,2800)","0","mstr_standard","I81";
;
CDS_LIB"mstr_standard"
BODY_TYPE"PLUMBING"
HDL_TAP"TRUE";
"B \NAC \NWC"1;
"S \NAC"
BN"11"65;
%"TAP"
"1","(-2675,2750)","0","mstr_standard","I82";
;
CDS_LIB"mstr_standard"
BODY_TYPE"PLUMBING"
HDL_TAP"TRUE";
"B \NAC \NWC"1;
"S \NAC"
BN"10"64;
%"TAP"
"1","(-2675,2700)","0","mstr_standard","I83";
;
CDS_LIB"mstr_standard"
BODY_TYPE"PLUMBING"
HDL_TAP"TRUE";
"B \NAC \NWC"1;
"S \NAC"
BN"9"63;
%"TAP"
"1","(-2675,2650)","0","mstr_standard","I84";
;
CDS_LIB"mstr_standard"
BODY_TYPE"PLUMBING"
HDL_TAP"TRUE";
"B \NAC \NWC"1;
"S \NAC"
BN"8"62;
%"TAP"
"1","(-2825,3000)","0","mstr_standard","I85";
;
CDS_LIB"mstr_standard"
BODY_TYPE"PLUMBING"
HDL_TAP"TRUE";
"B \NAC \NWC"2;
"S \NAC"
BN"10"52;
%"TAP"
"1","(-2825,2950)","0","mstr_standard","I86";
;
CDS_LIB"mstr_standard"
BODY_TYPE"PLUMBING"
HDL_TAP"TRUE";
"B \NAC \NWC"2;
"S \NAC"
BN"9"51;
%"TAP"
"1","(-2825,2900)","0","mstr_standard","I87";
;
CDS_LIB"mstr_standard"
BODY_TYPE"PLUMBING"
HDL_TAP"TRUE";
"B \NAC \NWC"2;
"S \NAC"
BN"8"50;
%"TAP"
"1","(-5300,3300)","2","mstr_standard","I88";
;
CDS_LIB"mstr_standard"
BODY_TYPE"PLUMBING"
HDL_TAP"TRUE";
"B \NAC \NWC"3;
"S \NAC"
BN"15"37;
%"TAP"
"1","(-5300,3250)","2","mstr_standard","I89";
;
CDS_LIB"mstr_standard"
BODY_TYPE"PLUMBING"
HDL_TAP"TRUE";
"B \NAC \NWC"3;
"S \NAC"
BN"14"36;
%"TAP"
"1","(-5450,2050)","2","mstr_standard","I9";
;
CDS_LIB"mstr_standard"
BODY_TYPE"PLUMBING"
HDL_TAP"TRUE";
"B \NAC \NWC"4;
"S \NAC"
BN"3"17;
%"TAP"
"1","(-5300,3200)","2","mstr_standard","I90";
;
CDS_LIB"mstr_standard"
BODY_TYPE"PLUMBING"
HDL_TAP"TRUE";
"B \NAC \NWC"3;
"S \NAC"
BN"13"35;
%"TAP"
"1","(-5300,3150)","2","mstr_standard","I91";
;
CDS_LIB"mstr_standard"
BODY_TYPE"PLUMBING"
HDL_TAP"TRUE";
"B \NAC \NWC"3;
"S \NAC"
BN"12"34;
%"TAP"
"1","(-5450,3550)","2","mstr_standard","I92";
;
CDS_LIB"mstr_standard"
BODY_TYPE"PLUMBING"
HDL_TAP"TRUE";
"B \NAC \NWC"4;
"S \NAC"
BN"15"6;
%"TAP"
"1","(-5450,3500)","2","mstr_standard","I93";
;
CDS_LIB"mstr_standard"
BODY_TYPE"PLUMBING"
HDL_TAP"TRUE";
"B \NAC \NWC"4;
"S \NAC"
BN"14"25;
%"TAP"
"1","(-5450,3450)","2","mstr_standard","I94";
;
CDS_LIB"mstr_standard"
BODY_TYPE"PLUMBING"
HDL_TAP"TRUE";
"B \NAC \NWC"4;
"S \NAC"
BN"13"24;
%"TAP"
"1","(-5450,3400)","2","mstr_standard","I95";
;
CDS_LIB"mstr_standard"
BODY_TYPE"PLUMBING"
HDL_TAP"TRUE";
"B \NAC \NWC"4;
"S \NAC"
BN"12"23;
%"TAP"
"1","(-5450,3050)","2","mstr_standard","I96";
;
CDS_LIB"mstr_standard"
BODY_TYPE"PLUMBING"
HDL_TAP"TRUE";
"B \NAC \NWC"4;
"S \NAC"
BN"11"22;
%"TAP"
"1","(-5300,2800)","2","mstr_standard","I97";
;
CDS_LIB"mstr_standard"
BODY_TYPE"PLUMBING"
HDL_TAP"TRUE";
"B \NAC \NWC"3;
"S \NAC"
BN"11"33;
%"TAP"
"1","(-5300,2700)","2","mstr_standard","I98";
;
CDS_LIB"mstr_standard"
BODY_TYPE"PLUMBING"
HDL_TAP"TRUE";
"B \NAC \NWC"3;
"S \NAC"
BN"9"31;
%"TAP"
"1","(-5300,2750)","2","mstr_standard","I99";
;
CDS_LIB"mstr_standard"
BODY_TYPE"PLUMBING"
HDL_TAP"TRUE";
"B \NAC \NWC"3;
"S \NAC"
BN"10"32;
END.
